(kicad_pcb
	(version 20260206)
	(generator "pcbnew")
	(generator_version "10.0")
	(general
		(thickness 1.6)
		(legacy_teardrops no)
	)
	(paper "A4")
	(title_block
		(title "dpb — 14545-sa.0730WZS0815.brd")
		(comment 1 "Honey Badger (Wiwynn) / footprints 517-523 of 1066")
	)
	(layers
		(0 "F.Cu" signal "TOP")
		(4 "In1.Cu" signal "L2GND")
		(6 "In2.Cu" signal "L3")
		(8 "In3.Cu" signal "L4VCC")
		(10 "In4.Cu" signal "L5VCC")
		(12 "In5.Cu" signal "L6")
		(14 "In6.Cu" signal "L7GND")
		(2 "B.Cu" signal "BOTTOM")
		(9 "F.Adhes" user "F.Adhesive")
		(11 "B.Adhes" user "B.Adhesive")
		(13 "F.Paste" user "Package Geometry/Pastemask Top")
		(15 "B.Paste" user "Package Geometry/Pastemask Bottom")
		(5 "F.SilkS" user "Ref Des/Silkscreen Top")
		(7 "B.SilkS" user "Ref Des/Silkscreen Bottom")
		(1 "F.Mask" user "Board Geometry/Soldermask Top")
		(3 "B.Mask" user "Board Geometry/Soldermask Bottom")
		(17 "Dwgs.User" user "User.Drawings")
		(19 "Cmts.User" user "User.Comments")
		(21 "Eco1.User" user "User.Eco1")
		(23 "Eco2.User" user "User.Eco2")
		(25 "Edge.Cuts" user "Board Geometry/Outline")
		(27 "Margin" user)
		(31 "F.CrtYd" user "Package Geometry/Place Bound Top")
		(29 "B.CrtYd" user "Package Geometry/Place Bound Bottom")
		(35 "F.Fab" user "Ref Des/Assembly Top")
		(33 "B.Fab" user "Ref Des/Assembly Bottom")
	)
	(footprint ""
		(layer "F.Cu")
		(at 166.509446 -461.552036)
		(property "Reference" "R381"
			(at 0 0 0)
			(layer "F.SilkS")
			(hide yes)
			(effects
				(font
					(size 1.27 1.27)
				)
			)
		)
		(property "Value" "4K7R2J-2-GP"
			(at 0.064008 -3.993896 0)
			(unlocked yes)
			(layer "F.Fab")
			(hide yes)
			(effects
				(font
					(size 1.016 1.016)
					(thickness 0.1524)
				)
			)
		)
		(property "Device Type" "R402H16"
			(at 0.064008 -5.517896 0)
			(unlocked yes)
			(layer "F.Fab")
			(hide yes)
			(effects
				(font
					(size 1.016 1.016)
					(thickness 0.1524)
				)
			)
		)
		(duplicate_pad_numbers_are_jumpers no)
		(fp_line
			(start -0.508 -0.9398)
			(end -0.508 0.9398)
			(stroke
				(width 0.1524)
				(type default)
			)
			(layer "F.SilkS")
		)
		(fp_line
			(start 0.508 -0.9398)
			(end -0.508 -0.9398)
			(stroke
				(width 0.1524)
				(type default)
			)
			(layer "F.SilkS")
		)
		(fp_rect
			(start -0.508 0.9398)
			(end 0.508 -0.9398)
			(stroke
				(width 0)
				(type default)
			)
			(fill no)
			(layer "F.CrtYd")
		)
		(fp_rect
			(start -0.508 0.9398)
			(end 0.508 -0.9398)
			(stroke
				(width 0)
				(type default)
			)
			(fill no)
			(layer "F.Fab")
		)
		(pad "1" smd custom
			(at 0 -0.4445)
			(size 0.1397 0.1397)
			(layers "F.Cu" "F.Mask" "F.Paste")
			(net "VOL_SEN_ADDR")
			(options
				(clearance outline)
				(anchor circle)
			)
			(primitives
				(gr_poly
					(pts
						(arc
							(start -0.1778 -0.2794)
							(mid -0.249642 -0.249642)
							(end -0.2794 -0.1778)
						)
						(arc
							(start -0.2794 0.1778)
							(mid -0.249642 0.249642)
							(end -0.1778 0.2794)
						)
						(arc
							(start 0.1778 0.2794)
							(mid 0.249642 0.249642)
							(end 0.2794 0.1778)
						)
						(arc
							(start 0.2794 -0.1778)
							(mid 0.249642 -0.249642)
							(end 0.1778 -0.2794)
						)
					)
					(width 0)
					(fill yes)
				)
			)
		)
		(pad "2" smd custom
			(at 0 0.4445)
			(size 0.1397 0.1397)
			(layers "F.Cu" "F.Mask" "F.Paste")
			(net "GND")
			(options
				(clearance outline)
				(anchor circle)
			)
			(primitives
				(gr_poly
					(pts
						(arc
							(start -0.1778 -0.2794)
							(mid -0.249642 -0.249642)
							(end -0.2794 -0.1778)
						)
						(arc
							(start -0.2794 0.1778)
							(mid -0.249642 0.249642)
							(end -0.1778 0.2794)
						)
						(arc
							(start 0.1778 0.2794)
							(mid 0.249642 0.249642)
							(end 0.2794 0.1778)
						)
						(arc
							(start 0.2794 -0.1778)
							(mid 0.249642 -0.249642)
							(end 0.1778 -0.2794)
						)
					)
					(width 0)
					(fill yes)
				)
			)
		)
	)
	(footprint ""
		(layer "F.Cu")
		(at 45.482256 -451.767702 90)
		(property "Reference" "R174"
			(at 0 0 90)
			(layer "F.SilkS")
			(hide yes)
			(effects
				(font
					(size 1.27 1.27)
				)
			)
		)
		(property "Value" "0R2J-2-GP"
			(at 0.064008 -3.993896 90)
			(unlocked yes)
			(layer "F.Fab")
			(hide yes)
			(effects
				(font
					(size 1.016 1.016)
					(thickness 0.1524)
				)
			)
		)
		(property "Device Type" "R402H16"
			(at 0.064008 -5.517896 90)
			(unlocked yes)
			(layer "F.Fab")
			(hide yes)
			(effects
				(font
					(size 1.016 1.016)
					(thickness 0.1524)
				)
			)
		)
		(duplicate_pad_numbers_are_jumpers no)
		(fp_line
			(start 0.508 -0.9398)
			(end -0.508 -0.9398)
			(stroke
				(width 0.1524)
				(type default)
			)
			(layer "F.SilkS")
		)
		(fp_line
			(start -0.508 -0.9398)
			(end -0.508 0.9398)
			(stroke
				(width 0.1524)
				(type default)
			)
			(layer "F.SilkS")
		)
		(fp_rect
			(start -0.508 0.9398)
			(end 0.508 -0.9398)
			(stroke
				(width 0)
				(type default)
			)
			(fill no)
			(layer "F.CrtYd")
		)
		(fp_rect
			(start -0.508 0.9398)
			(end 0.508 -0.9398)
			(stroke
				(width 0)
				(type default)
			)
			(fill no)
			(layer "F.Fab")
		)
		(pad "1" smd custom
			(at 0 -0.4445 90)
			(size 0.1397 0.1397)
			(layers "F.Cu" "F.Mask" "F.Paste")
			(net "FLT_NET_HDD5")
			(options
				(clearance outline)
				(anchor circle)
			)
			(primitives
				(gr_poly
					(pts
						(arc
							(start -0.1778 -0.2794)
							(mid -0.249642 -0.249642)
							(end -0.2794 -0.1778)
						)
						(arc
							(start -0.2794 0.1778)
							(mid -0.249642 0.249642)
							(end -0.1778 0.2794)
						)
						(arc
							(start 0.1778 0.2794)
							(mid 0.249642 0.249642)
							(end 0.2794 0.1778)
						)
						(arc
							(start 0.2794 -0.1778)
							(mid 0.249642 -0.249642)
							(end 0.1778 -0.2794)
						)
					)
					(width 0)
					(fill yes)
				)
			)
		)
		(pad "2" smd custom
			(at 0 0.4445 90)
			(size 0.1397 0.1397)
			(layers "F.Cu" "F.Mask" "F.Paste")
			(net "FLT_HDD5_DRIVE")
			(options
				(clearance outline)
				(anchor circle)
			)
			(primitives
				(gr_poly
					(pts
						(arc
							(start -0.1778 -0.2794)
							(mid -0.249642 -0.249642)
							(end -0.2794 -0.1778)
						)
						(arc
							(start -0.2794 0.1778)
							(mid -0.249642 0.249642)
							(end -0.1778 0.2794)
						)
						(arc
							(start 0.1778 0.2794)
							(mid 0.249642 0.249642)
							(end 0.2794 0.1778)
						)
						(arc
							(start 0.2794 -0.1778)
							(mid 0.249642 -0.249642)
							(end 0.1778 -0.2794)
						)
					)
					(width 0)
					(fill yes)
				)
			)
		)
	)
	(footprint ""
		(layer "F.Cu")
		(at 227.499926 -41.159938 180)
		(property "Reference" "LED5"
			(at 0 0 180)
			(layer "F.SilkS")
			(hide yes)
			(effects
				(font
					(size 1.27 1.27)
				)
			)
		)
		(property "Value" "LED-RB-4-GP"
			(at 5.88899 1.80848 180)
			(unlocked yes)
			(layer "F.Fab")
			(hide yes)
			(effects
				(font
					(size 1.016 1.016)
					(thickness 0.1524)
				)
			)
		)
		(property "Device Type" "LED1613-4PH20"
			(at 5.88899 0.28448 180)
			(unlocked yes)
			(layer "F.Fab")
			(hide yes)
			(effects
				(font
					(size 1.016 1.016)
					(thickness 0.1524)
				)
			)
		)
		(duplicate_pad_numbers_are_jumpers no)
		(fp_line
			(start 1.4478 0.9652)
			(end -1.4478 0.9652)
			(stroke
				(width 0.1524)
				(type default)
			)
			(layer "F.SilkS")
		)
		(fp_line
			(start 1.4478 -0.9652)
			(end 1.4478 0.9652)
			(stroke
				(width 0.1524)
				(type default)
			)
			(layer "F.SilkS")
		)
		(fp_line
			(start -1.4478 0.9652)
			(end -1.4478 -0.9652)
			(stroke
				(width 0.1524)
				(type default)
			)
			(layer "F.SilkS")
		)
		(fp_line
			(start -1.4478 0.9652)
			(end -1.4478 -0.9652)
			(stroke
				(width 0.508)
				(type default)
			)
			(layer "F.SilkS")
		)
		(fp_line
			(start -1.4478 -0.9652)
			(end 1.4478 -0.9652)
			(stroke
				(width 0.1524)
				(type default)
			)
			(layer "F.SilkS")
		)
		(fp_rect
			(start -0.8001 0.6477)
			(end 0.8001 -0.6477)
			(stroke
				(width 0)
				(type default)
			)
			(fill no)
			(layer "F.CrtYd")
		)
		(fp_poly
			(pts
				(xy -1.7018 1.2192) (xy -1.7018 -0.06223) (xy -0.8001 -0.06223) (xy -0.8001 0.6477) (xy 0.8001 0.6477)
				(xy 0.8001 -0.6477) (xy -0.8001 -0.6477) (xy -0.8001 -0.0635) (xy -1.7018 -0.0635) (xy -1.7018 -1.2192)
				(xy 1.7018 -1.2192) (xy 1.7018 1.2192)
			)
			(stroke
				(width 0)
				(type default)
			)
			(fill no)
			(layer "F.CrtYd")
		)
		(fp_rect
			(start -1.7018 1.2192)
			(end 1.7018 -1.2192)
			(stroke
				(width 0)
				(type default)
			)
			(fill no)
			(layer "F.Fab")
		)
		(pad "1" smd rect
			(at -0.73025 0.4064 180)
			(size 0.9144 0.6096)
			(layers "F.Cu" "F.Mask" "F.Paste")
			(net "DRV_ACT_NET4")
		)
		(pad "2" smd rect
			(at -0.73025 -0.4064 180)
			(size 0.9144 0.6096)
			(layers "F.Cu" "F.Mask" "F.Paste")
			(net "FLT_NET_HDD4")
		)
		(pad "3" smd rect
			(at 0.73025 -0.4064 180)
			(size 0.9144 0.6096)
			(layers "F.Cu" "F.Mask" "F.Paste")
			(net "FLT_HDD4")
		)
		(pad "4" smd rect
			(at 0.73025 0.4064 180)
			(size 0.9144 0.6096)
			(layers "F.Cu" "F.Mask" "F.Paste")
			(net "DRV_ACT_4")
		)
	)
	(footprint ""
		(layer "F.Cu")
		(at 79.781146 -7.013702)
		(property "Reference" "C334"
			(at 0 0 0)
			(layer "F.SilkS")
			(hide yes)
			(effects
				(font
					(size 1.27 1.27)
				)
			)
		)
		(property "Value" "SC10U25V6KX-1GP"
			(at -0.0762 -5.1308 0)
			(unlocked yes)
			(layer "F.Fab")
			(hide yes)
			(effects
				(font
					(size 1.016 1.016)
					(thickness 0.1524)
				)
			)
		)
		(property "Device Type" "C1206H71"
			(at -0.127 -6.6548 0)
			(unlocked yes)
			(layer "F.Fab")
			(hide yes)
			(effects
				(font
					(size 1.016 1.016)
					(thickness 0.1524)
				)
			)
		)
		(duplicate_pad_numbers_are_jumpers no)
		(fp_line
			(start -1.016 -2.2352)
			(end 1.016 -2.2352)
			(stroke
				(width 0.1524)
				(type default)
			)
			(layer "F.SilkS")
		)
		(fp_line
			(start -1.016 -0.8382)
			(end -1.016 -2.2352)
			(stroke
				(width 0.1524)
				(type default)
			)
			(layer "F.SilkS")
		)
		(fp_line
			(start -1.016 2.2352)
			(end -1.016 0.8382)
			(stroke
				(width 0.1524)
				(type default)
			)
			(layer "F.SilkS")
		)
		(fp_line
			(start 1.016 -2.2352)
			(end 1.016 -0.8382)
			(stroke
				(width 0.1524)
				(type default)
			)
			(layer "F.SilkS")
		)
		(fp_line
			(start 1.016 0.8382)
			(end 1.016 2.2352)
			(stroke
				(width 0.1524)
				(type default)
			)
			(layer "F.SilkS")
		)
		(fp_line
			(start 1.016 2.2352)
			(end -1.016 2.2352)
			(stroke
				(width 0.1524)
				(type default)
			)
			(layer "F.SilkS")
		)
		(fp_rect
			(start -1.0922 2.3114)
			(end 1.0922 -2.3114)
			(stroke
				(width 0)
				(type default)
			)
			(fill no)
			(layer "F.CrtYd")
		)
		(fp_poly
			(pts
				(xy 1.0922 -2.3114) (xy 1.0922 2.3114) (xy -1.0922 2.3114) (xy -1.0922 -2.3114)
			)
			(stroke
				(width 0)
				(type default)
			)
			(fill no)
			(layer "F.Fab")
		)
		(pad "1" smd rect
			(at 0 -1.397)
			(size 1.651 1.27)
			(layers "F.Cu" "F.Mask" "F.Paste")
			(net "P12V_HDD14")
		)
		(pad "2" smd rect
			(at 0 1.397)
			(size 1.651 1.27)
			(layers "F.Cu" "F.Mask" "F.Paste")
			(net "GND")
		)
	)
	(footprint ""
		(layer "F.Cu")
		(at 214.9348 -172.1358 -90)
		(property "Reference" "R369"
			(at 0 0 270)
			(layer "F.SilkS")
			(hide yes)
			(effects
				(font
					(size 1.27 1.27)
				)
			)
		)
		(property "Value" "0R2J-2-GP"
			(at 0.064008 -3.993896 270)
			(unlocked yes)
			(layer "F.Fab")
			(hide yes)
			(effects
				(font
					(size 1.016 1.016)
					(thickness 0.1524)
				)
			)
		)
		(property "Device Type" "R402H16"
			(at 0.064008 -5.517896 270)
			(unlocked yes)
			(layer "F.Fab")
			(hide yes)
			(effects
				(font
					(size 1.016 1.016)
					(thickness 0.1524)
				)
			)
		)
		(duplicate_pad_numbers_are_jumpers no)
		(fp_line
			(start -0.508 -0.9398)
			(end -0.508 0.9398)
			(stroke
				(width 0.1524)
				(type default)
			)
			(layer "F.SilkS")
		)
		(fp_line
			(start 0.508 -0.9398)
			(end -0.508 -0.9398)
			(stroke
				(width 0.1524)
				(type default)
			)
			(layer "F.SilkS")
		)
		(fp_rect
			(start -0.508 0.9398)
			(end 0.508 -0.9398)
			(stroke
				(width 0)
				(type default)
			)
			(fill no)
			(layer "F.CrtYd")
		)
		(fp_rect
			(start -0.508 0.9398)
			(end 0.508 -0.9398)
			(stroke
				(width 0)
				(type default)
			)
			(fill no)
			(layer "F.Fab")
		)
		(pad "1" smd custom
			(at 0 -0.4445 270)
			(size 0.1397 0.1397)
			(layers "F.Cu" "F.Mask" "F.Paste")
			(net "HDD_PRSNT_NET3")
			(options
				(clearance outline)
				(anchor circle)
			)
			(primitives
				(gr_poly
					(pts
						(arc
							(start -0.1778 -0.2794)
							(mid -0.249642 -0.249642)
							(end -0.2794 -0.1778)
						)
						(arc
							(start -0.2794 0.1778)
							(mid -0.249642 0.249642)
							(end -0.1778 0.2794)
						)
						(arc
							(start 0.1778 0.2794)
							(mid 0.249642 0.249642)
							(end 0.2794 0.1778)
						)
						(arc
							(start 0.2794 -0.1778)
							(mid 0.249642 -0.249642)
							(end 0.1778 -0.2794)
						)
					)
					(width 0)
					(fill yes)
				)
			)
		)
		(pad "2" smd custom
			(at 0 0.4445 270)
			(size 0.1397 0.1397)
			(layers "F.Cu" "F.Mask" "F.Paste")
			(net "HDD3_LED_B")
			(options
				(clearance outline)
				(anchor circle)
			)
			(primitives
				(gr_poly
					(pts
						(arc
							(start -0.1778 -0.2794)
							(mid -0.249642 -0.249642)
							(end -0.2794 -0.1778)
						)
						(arc
							(start -0.2794 0.1778)
							(mid -0.249642 0.249642)
							(end -0.1778 0.2794)
						)
						(arc
							(start 0.1778 0.2794)
							(mid 0.249642 0.249642)
							(end 0.2794 0.1778)
						)
						(arc
							(start 0.2794 -0.1778)
							(mid 0.249642 -0.249642)
							(end 0.1778 -0.2794)
						)
					)
					(width 0)
					(fill yes)
				)
			)
		)
	)
	(footprint ""
		(layer "F.Cu")
		(at 24.129746 -286.6517 90)
		(property "Reference" "U23"
			(at 0 0 90)
			(layer "F.SilkS")
			(hide yes)
			(effects
				(font
					(size 1.27 1.27)
				)
			)
		)
		(property "Value" "P2003EVG-GP"
			(at 0 -11.1252 90)
			(unlocked yes)
			(layer "F.Fab")
			(hide yes)
			(effects
				(font
					(size 1.016 1.016)
					(thickness 0.1524)
				)
			)
		)
		(property "Device Type" "SOIC8H79"
			(at 0 -12.6492 90)
			(unlocked yes)
			(layer "F.Fab")
			(hide yes)
			(effects
				(font
					(size 1.016 1.016)
					(thickness 0.1524)
				)
			)
		)
		(duplicate_pad_numbers_are_jumpers no)
		(fp_line
			(start 2.1336 -1.4224)
			(end -2.7432 -1.4224)
			(stroke
				(width 0.1524)
				(type default)
			)
			(layer "F.SilkS")
		)
		(fp_line
			(start -2.7432 -1.4224)
			(end -2.7432 1.4224)
			(stroke
				(width 0.1524)
				(type default)
			)
			(layer "F.SilkS")
		)
		(fp_line
			(start -2.7432 -0.508)
			(end -2.2352 0)
			(stroke
				(width 0.1524)
				(type default)
			)
			(layer "F.SilkS")
		)
		(fp_line
			(start -2.2352 0)
			(end -2.7432 0.508)
			(stroke
				(width 0.1524)
				(type default)
			)
			(layer "F.SilkS")
		)
		(fp_line
			(start 2.1336 1.4224)
			(end 2.1336 -1.4224)
			(stroke
				(width 0.1524)
				(type default)
			)
			(layer "F.SilkS")
		)
		(fp_line
			(start -2.7432 1.4224)
			(end 2.1336 1.4224)
			(stroke
				(width 0.1524)
				(type default)
			)
			(layer "F.SilkS")
		)
		(fp_line
			(start -2.6162 3.429)
			(end -2.6162 1.4732)
			(stroke
				(width 0.4064)
				(type default)
			)
			(layer "F.SilkS")
		)
		(fp_poly
			(pts
				(xy 2.2098 -1.4224) (xy 2.2098 1.4224) (xy -2.2225 1.4224) (xy -2.2225 -1.4224)
			)
			(stroke
				(width 0)
				(type default)
			)
			(fill yes)
			(layer "F.SilkS")
		)
		(fp_rect
			(start -2.4511 2.9972)
			(end 2.4511 -2.9972)
			(stroke
				(width 0)
				(type default)
			)
			(fill no)
			(layer "F.CrtYd")
		)
		(fp_poly
			(pts
				(xy -2.8194 3.6322) (xy -2.8194 -3.6322) (xy 2.8194 -3.6322) (xy 2.8194 -2.2987) (xy 2.4511 -2.2987)
				(xy 2.4511 -2.9972) (xy -2.4511 -2.9972) (xy -2.4511 2.9972) (xy 2.4511 2.9972) (xy 2.4511 -2.286)
				(xy 2.8194 -2.286) (xy 2.8194 3.6322)
			)
			(stroke
				(width 0)
				(type default)
			)
			(fill no)
			(layer "F.CrtYd")
		)
		(fp_rect
			(start -2.8194 3.6322)
			(end 2.8194 -3.6322)
			(stroke
				(width 0)
				(type default)
			)
			(fill no)
			(layer "F.Fab")
		)
		(pad "1" smd rect
			(at -1.905 2.54 90)
			(size 0.635 1.651)
			(layers "F.Cu" "F.Mask" "F.Paste")
			(net "P12V")
		)
		(pad "2" smd rect
			(at -0.635 2.54 90)
			(size 0.635 1.651)
			(layers "F.Cu" "F.Mask" "F.Paste")
			(net "P12V")
		)
		(pad "3" smd rect
			(at 0.635 2.54 90)
			(size 0.635 1.651)
			(layers "F.Cu" "F.Mask" "F.Paste")
			(net "P12V")
		)
		(pad "4" smd rect
			(at 1.905 2.54 90)
			(size 0.635 1.651)
			(layers "F.Cu" "F.Mask" "F.Paste")
			(net "SW_HDD7_N")
		)
		(pad "5" smd rect
			(at 1.905 -2.54 90)
			(size 0.635 1.651)
			(layers "F.Cu" "F.Mask" "F.Paste")
			(net "P12V_HDD7")
		)
		(pad "6" smd rect
			(at 0.635 -2.54 90)
			(size 0.635 1.651)
			(layers "F.Cu" "F.Mask" "F.Paste")
			(net "P12V_HDD7")
		)
		(pad "7" smd rect
			(at -0.635 -2.54 90)
			(size 0.635 1.651)
			(layers "F.Cu" "F.Mask" "F.Paste")
			(net "P12V_HDD7")
		)
		(pad "8" smd rect
			(at -1.905 -2.54 90)
			(size 0.635 1.651)
			(layers "F.Cu" "F.Mask" "F.Paste")
			(net "P12V_HDD7")
		)
	)
	(footprint ""
		(layer "F.Cu")
		(at 35.940746 -112.296702 180)
		(property "Reference" "R287"
			(at 0 0 180)
			(layer "F.SilkS")
			(hide yes)
			(effects
				(font
					(size 1.27 1.27)
				)
			)
		)
		(property "Value" "1KR2F-3-GP"
			(at 0.064008 -3.993896 180)
			(unlocked yes)
			(layer "F.Fab")
			(hide yes)
			(effects
				(font
					(size 1.016 1.016)
					(thickness 0.1524)
				)
			)
		)
		(property "Device Type" "R402H16"
			(at 0.064008 -5.517896 180)
			(unlocked yes)
			(layer "F.Fab")
			(hide yes)
			(effects
				(font
					(size 1.016 1.016)
					(thickness 0.1524)
				)
			)
		)
		(duplicate_pad_numbers_are_jumpers no)
		(fp_line
			(start 0.508 -0.9398)
			(end -0.508 -0.9398)
			(stroke
				(width 0.1524)
				(type default)
			)
			(layer "F.SilkS")
		)
		(fp_line
			(start -0.508 -0.9398)
			(end -0.508 0.9398)
			(stroke
				(width 0.1524)
				(type default)
			)
			(layer "F.SilkS")
		)
		(fp_rect
			(start -0.508 0.9398)
			(end 0.508 -0.9398)
			(stroke
				(width 0)
				(type default)
			)
			(fill no)
			(layer "F.CrtYd")
		)
		(fp_rect
			(start -0.508 0.9398)
			(end 0.508 -0.9398)
			(stroke
				(width 0)
				(type default)
			)
			(fill no)
			(layer "F.Fab")
		)
		(pad "1" smd custom
			(at 0 -0.4445 180)
			(size 0.1397 0.1397)
			(layers "F.Cu" "F.Mask" "F.Paste")
			(net "P3V3")
			(options
				(clearance outline)
				(anchor circle)
			)
			(primitives
				(gr_poly
					(pts
						(arc
							(start -0.1778 -0.2794)
							(mid -0.249642 -0.249642)
							(end -0.2794 -0.1778)
						)
						(arc
							(start -0.2794 0.1778)
							(mid -0.249642 0.249642)
							(end -0.1778 0.2794)
						)
						(arc
							(start 0.1778 0.2794)
							(mid 0.249642 0.249642)
							(end 0.2794 0.1778)
						)
						(arc
							(start 0.2794 -0.1778)
							(mid 0.249642 -0.249642)
							(end 0.1778 -0.2794)
						)
					)
					(width 0)
					(fill yes)
				)
			)
		)
		(pad "2" smd custom
			(at 0 0.4445 180)
			(size 0.1397 0.1397)
			(layers "F.Cu" "F.Mask" "F.Paste")
			(net "SW_PWR_HDD13")
			(options
				(clearance outline)
				(anchor circle)
			)
			(primitives
				(gr_poly
					(pts
						(arc
							(start -0.1778 -0.2794)
							(mid -0.249642 -0.249642)
							(end -0.2794 -0.1778)
						)
						(arc
							(start -0.2794 0.1778)
							(mid -0.249642 0.249642)
							(end -0.1778 0.2794)
						)
						(arc
							(start 0.1778 0.2794)
							(mid 0.249642 0.249642)
							(end 0.2794 0.1778)
						)
						(arc
							(start 0.2794 -0.1778)
							(mid 0.249642 -0.249642)
							(end 0.1778 -0.2794)
						)
					)
					(width 0)
					(fill yes)
				)
			)
		)
	)
)
